(kicad_pcb
	(version 20260206)
	(generator "pcbnew")
	(generator_version "10.0")
	(general
		(thickness 1.6)
		(legacy_teardrops no)
	)
	(paper "A4")
	(title_block
		(title "03242023_DA0F0TMBIJ0_F0T_Motherboard_J_brd_V01_OCP.brd")
		(comment 1 "Grand Teton / footprints 2473-2479 of 6105")
	)
	(layers
		(0 "F.Cu" signal "TOP")
		(4 "In1.Cu" signal "GND")
		(6 "In2.Cu" signal "IN1")
		(8 "In3.Cu" signal "GND1")
		(10 "In4.Cu" signal "IN2")
		(12 "In5.Cu" signal "GND2")
		(14 "In6.Cu" signal "IN3")
		(16 "In7.Cu" signal "GND3")
		(18 "In8.Cu" signal "VCC")
		(20 "In9.Cu" signal "VCC1")
		(22 "In10.Cu" signal "GND4")
		(24 "In11.Cu" signal "IN4")
		(26 "In12.Cu" signal "GND5")
		(28 "In13.Cu" signal "IN5")
		(30 "In14.Cu" signal "GND6")
		(32 "In15.Cu" signal "IN6")
		(34 "In16.Cu" signal "GND7")
		(2 "B.Cu" signal "BOTTOM")
		(9 "F.Adhes" user "F.Adhesive")
		(11 "B.Adhes" user "B.Adhesive")
		(13 "F.Paste" user "Package Geometry/Pastemask Top")
		(15 "B.Paste" user "Package Geometry/Pastemask Bottom")
		(5 "F.SilkS" user "Ref Des/Silkscreen Top")
		(7 "B.SilkS" user "Ref Des/Silkscreen Bottom")
		(1 "F.Mask" user "Board Geometry/Soldermask Top")
		(3 "B.Mask" user "Board Geometry/Soldermask Bottom")
		(17 "Dwgs.User" user "User.Drawings")
		(19 "Cmts.User" user "User.Comments")
		(21 "Eco1.User" user "User.Eco1")
		(23 "Eco2.User" user "User.Eco2")
		(25 "Edge.Cuts" user "Board Geometry/Outline")
		(27 "Margin" user)
		(31 "F.CrtYd" user "Package Geometry/Place Bound Top")
		(29 "B.CrtYd" user "Package Geometry/Place Bound Bottom")
		(35 "F.Fab" user "Ref Des/Assembly Top")
		(33 "B.Fab" user "Ref Des/Assembly Bottom")
	)
	(footprint ""
		(layer "F.Cu")
		(at 54.811168 -168.683178)
		(property "Reference" "PC375"
			(at 0 0 0)
			(layer "F.SilkS")
			(hide yes)
			(effects
				(font
					(size 1.27 1.27)
				)
			)
		)
		(property "Value" ""
			(at 0 0 0)
			(layer "F.Fab")
			(effects
				(font
					(size 1.27 1.27)
				)
			)
		)
		(duplicate_pad_numbers_are_jumpers no)
		(fp_line
			(start -0.7874 -0.4064)
			(end 0.7874 -0.4064)
			(stroke
				(width 0.1524)
				(type default)
			)
			(layer "F.SilkS")
		)
		(fp_line
			(start -0.7874 0.4064)
			(end -0.7874 -0.4064)
			(stroke
				(width 0.1524)
				(type default)
			)
			(layer "F.SilkS")
		)
		(fp_line
			(start 0.7874 -0.4064)
			(end 0.7874 0.4064)
			(stroke
				(width 0.1524)
				(type default)
			)
			(layer "F.SilkS")
		)
		(fp_line
			(start 0.7874 0.4064)
			(end -0.7874 0.4064)
			(stroke
				(width 0.1524)
				(type default)
			)
			(layer "F.SilkS")
		)
		(fp_line
			(start -0.67945 -0.305054)
			(end -0.12065 -0.305054)
			(stroke
				(width 0.1)
				(type default)
			)
			(layer "F.Fab")
		)
		(fp_line
			(start -0.67945 0.3048)
			(end -0.67945 -0.305054)
			(stroke
				(width 0.1)
				(type default)
			)
			(layer "F.Fab")
		)
		(fp_line
			(start -0.12065 -0.305054)
			(end -0.12065 -0.2794)
			(stroke
				(width 0.1)
				(type default)
			)
			(layer "F.Fab")
		)
		(fp_line
			(start -0.12065 -0.2794)
			(end 0.12065 -0.2794)
			(stroke
				(width 0.1)
				(type default)
			)
			(layer "F.Fab")
		)
		(fp_line
			(start -0.12065 0.2794)
			(end -0.12065 0.3048)
			(stroke
				(width 0.1)
				(type default)
			)
			(layer "F.Fab")
		)
		(fp_line
			(start -0.12065 0.3048)
			(end -0.67945 0.3048)
			(stroke
				(width 0.1)
				(type default)
			)
			(layer "F.Fab")
		)
		(fp_line
			(start 0.120396 0.2794)
			(end -0.12065 0.2794)
			(stroke
				(width 0.1)
				(type default)
			)
			(layer "F.Fab")
		)
		(fp_line
			(start 0.120396 0.3048)
			(end 0.120396 0.2794)
			(stroke
				(width 0.1)
				(type default)
			)
			(layer "F.Fab")
		)
		(fp_line
			(start 0.12065 -0.3048)
			(end 0.67945 -0.3048)
			(stroke
				(width 0.1)
				(type default)
			)
			(layer "F.Fab")
		)
		(fp_line
			(start 0.12065 -0.2794)
			(end 0.12065 -0.3048)
			(stroke
				(width 0.1)
				(type default)
			)
			(layer "F.Fab")
		)
		(fp_line
			(start 0.67945 -0.3048)
			(end 0.67945 0.3048)
			(stroke
				(width 0.1)
				(type default)
			)
			(layer "F.Fab")
		)
		(fp_line
			(start 0.67945 0.3048)
			(end 0.120396 0.3048)
			(stroke
				(width 0.1)
				(type default)
			)
			(layer "F.Fab")
		)
		(pad "1" smd circle
			(at -0.40005 0)
			(size 0 0)
			(layers "F.Cu" "F.Mask" "F.Paste")
			(net "SW_P12V_PVCCINFAON_CPU1_FLT")
		)
		(pad "2" smd circle
			(at 0.40005 0)
			(size 0 0)
			(layers "F.Cu" "F.Mask" "F.Paste")
			(net "GND")
		)
	)
	(footprint ""
		(layer "F.Cu")
		(at 136.519158 -354.434902)
		(property "Reference" "H49"
			(at -2.63906 -5.052568 0)
			(unlocked yes)
			(layer "F.SilkS")
			(effects
				(font
					(size 0.7874 0.5842)
					(thickness 0.1524)
				)
				(justify left)
			)
		)
		(property "Value" ""
			(at 0 0 0)
			(layer "F.Fab")
			(effects
				(font
					(size 1.27 1.27)
				)
			)
		)
		(duplicate_pad_numbers_are_jumpers no)
		(pad "1" thru_hole circle
			(at 0 0)
			(size 8.001 8.001)
			(drill 3.2004)
			(layers "*.Cu" "*.Mask")
			(remove_unused_layers no)
			(net "GND")
			(clearance -2.1463)
			(padstack
				(mode front_inner_back)
				(layer "Inner"
					(shape circle)
					(size 5.0038 5.0038)
					(clearance -0.6477)
				)
				(layer "B.Cu"
					(shape circle)
					(size 8.001 8.001)
					(clearance -2.1463)
				)
			)
		)
	)
	(footprint ""
		(layer "F.Cu")
		(at 20.60956 -77.028548)
		(property "Reference" "R3133"
			(at 0 0 0)
			(layer "F.SilkS")
			(hide yes)
			(effects
				(font
					(size 1.27 1.27)
				)
			)
		)
		(property "Value" ""
			(at 0 0 0)
			(layer "F.Fab")
			(effects
				(font
					(size 1.27 1.27)
				)
			)
		)
		(duplicate_pad_numbers_are_jumpers no)
		(fp_line
			(start -0.7874 -0.4064)
			(end 0.7874 -0.4064)
			(stroke
				(width 0.1524)
				(type default)
			)
			(layer "F.SilkS")
		)
		(fp_line
			(start -0.7874 0.4064)
			(end -0.7874 -0.4064)
			(stroke
				(width 0.1524)
				(type default)
			)
			(layer "F.SilkS")
		)
		(fp_line
			(start 0.7874 -0.4064)
			(end 0.7874 0.4064)
			(stroke
				(width 0.1524)
				(type default)
			)
			(layer "F.SilkS")
		)
		(fp_line
			(start 0.7874 0.4064)
			(end -0.7874 0.4064)
			(stroke
				(width 0.1524)
				(type default)
			)
			(layer "F.SilkS")
		)
		(fp_line
			(start -0.67945 -0.305054)
			(end -0.12065 -0.305054)
			(stroke
				(width 0.1)
				(type default)
			)
			(layer "F.Fab")
		)
		(fp_line
			(start -0.67945 0.3048)
			(end -0.67945 -0.305054)
			(stroke
				(width 0.1)
				(type default)
			)
			(layer "F.Fab")
		)
		(fp_line
			(start -0.12065 -0.305054)
			(end -0.12065 -0.2794)
			(stroke
				(width 0.1)
				(type default)
			)
			(layer "F.Fab")
		)
		(fp_line
			(start -0.12065 -0.2794)
			(end 0.12065 -0.2794)
			(stroke
				(width 0.1)
				(type default)
			)
			(layer "F.Fab")
		)
		(fp_line
			(start -0.12065 0.2794)
			(end -0.12065 0.3048)
			(stroke
				(width 0.1)
				(type default)
			)
			(layer "F.Fab")
		)
		(fp_line
			(start -0.12065 0.3048)
			(end -0.67945 0.3048)
			(stroke
				(width 0.1)
				(type default)
			)
			(layer "F.Fab")
		)
		(fp_line
			(start 0.120396 0.2794)
			(end -0.12065 0.2794)
			(stroke
				(width 0.1)
				(type default)
			)
			(layer "F.Fab")
		)
		(fp_line
			(start 0.120396 0.3048)
			(end 0.120396 0.2794)
			(stroke
				(width 0.1)
				(type default)
			)
			(layer "F.Fab")
		)
		(fp_line
			(start 0.12065 -0.3048)
			(end 0.67945 -0.3048)
			(stroke
				(width 0.1)
				(type default)
			)
			(layer "F.Fab")
		)
		(fp_line
			(start 0.12065 -0.2794)
			(end 0.12065 -0.3048)
			(stroke
				(width 0.1)
				(type default)
			)
			(layer "F.Fab")
		)
		(fp_line
			(start 0.67945 -0.3048)
			(end 0.67945 0.3048)
			(stroke
				(width 0.1)
				(type default)
			)
			(layer "F.Fab")
		)
		(fp_line
			(start 0.67945 0.3048)
			(end 0.120396 0.3048)
			(stroke
				(width 0.1)
				(type default)
			)
			(layer "F.Fab")
		)
		(pad "1" smd circle
			(at -0.40005 0)
			(size 0 0)
			(layers "F.Cu" "F.Mask" "F.Paste")
			(net "P3V3_AUX")
		)
		(pad "2" smd circle
			(at 0.40005 0)
			(size 0 0)
			(layers "F.Cu" "F.Mask" "F.Paste")
			(net "OCP_V3_2_PRSNT0_R_N")
		)
	)
	(footprint ""
		(layer "F.Cu")
		(at 268.833092 -407.416 -90)
		(property "Reference" "PR2532"
			(at 0 0 270)
			(layer "F.SilkS")
			(hide yes)
			(effects
				(font
					(size 1.27 1.27)
				)
			)
		)
		(property "Value" ""
			(at 0 0 270)
			(layer "F.Fab")
			(effects
				(font
					(size 1.27 1.27)
				)
			)
		)
		(duplicate_pad_numbers_are_jumpers no)
		(fp_line
			(start -3.9878 3.5814)
			(end -3.9878 -3.5814)
			(stroke
				(width 0.1524)
				(type default)
			)
			(layer "F.SilkS")
		)
		(fp_line
			(start 3.9878 3.5814)
			(end -3.9878 3.5814)
			(stroke
				(width 0.1524)
				(type default)
			)
			(layer "F.SilkS")
		)
		(fp_line
			(start -3.9878 -3.5814)
			(end 3.9878 -3.5814)
			(stroke
				(width 0.1524)
				(type default)
			)
			(layer "F.SilkS")
		)
		(fp_line
			(start 3.9878 -3.5814)
			(end 3.9878 3.5814)
			(stroke
				(width 0.1524)
				(type default)
			)
			(layer "F.SilkS")
		)
		(fp_line
			(start -3.5306 3.353054)
			(end -3.5306 -3.353054)
			(stroke
				(width 0.1)
				(type default)
			)
			(layer "F.Fab")
		)
		(fp_line
			(start 3.5306 3.353054)
			(end -3.5306 3.353054)
			(stroke
				(width 0.1)
				(type default)
			)
			(layer "F.Fab")
		)
		(fp_line
			(start -3.5306 -3.353054)
			(end 3.5306 -3.353054)
			(stroke
				(width 0.1)
				(type default)
			)
			(layer "F.Fab")
		)
		(fp_line
			(start 3.5306 -3.353054)
			(end 3.5306 3.353054)
			(stroke
				(width 0.1)
				(type default)
			)
			(layer "F.Fab")
		)
		(pad "1A" smd rect
			(at -2.249932 0 90)
			(size 3.2004 6.858)
			(layers "F.Cu" "F.Mask" "F.Paste")
			(net "P12V_PSU")
		)
		(pad "1B" smd rect
			(at -0.776732 0 270)
			(size 0.254 0.508)
			(layers "F.Cu" "F.Mask" "F.Paste")
			(net "P12V_HSC_SENSE2_R2_P")
		)
		(pad "2A" smd rect
			(at 2.249932 0 90)
			(size 3.2004 6.858)
			(layers "F.Cu" "F.Mask" "F.Paste")
			(net "P12V_MAIN_R")
		)
		(pad "2B" smd rect
			(at 0.776732 0 270)
			(size 0.254 0.508)
			(layers "F.Cu" "F.Mask" "F.Paste")
			(net "P12V_HSC_SENSE2_R2_N")
		)
	)
	(footprint ""
		(layer "F.Cu")
		(at 13.800582 -408.516836 -90)
		(property "Reference" "R2694"
			(at 0 0 270)
			(layer "F.SilkS")
			(hide yes)
			(effects
				(font
					(size 1.27 1.27)
				)
			)
		)
		(property "Value" ""
			(at 0 0 270)
			(layer "F.Fab")
			(effects
				(font
					(size 1.27 1.27)
				)
			)
		)
		(duplicate_pad_numbers_are_jumpers no)
		(fp_line
			(start -0.7874 0.4064)
			(end -0.7874 -0.4064)
			(stroke
				(width 0.1524)
				(type default)
			)
			(layer "F.SilkS")
		)
		(fp_line
			(start 0.7874 0.4064)
			(end -0.7874 0.4064)
			(stroke
				(width 0.1524)
				(type default)
			)
			(layer "F.SilkS")
		)
		(fp_line
			(start -0.7874 -0.4064)
			(end 0.7874 -0.4064)
			(stroke
				(width 0.1524)
				(type default)
			)
			(layer "F.SilkS")
		)
		(fp_line
			(start 0.7874 -0.4064)
			(end 0.7874 0.4064)
			(stroke
				(width 0.1524)
				(type default)
			)
			(layer "F.SilkS")
		)
		(fp_line
			(start -0.67945 0.3048)
			(end -0.67945 -0.305054)
			(stroke
				(width 0.1)
				(type default)
			)
			(layer "F.Fab")
		)
		(fp_line
			(start -0.12065 0.3048)
			(end -0.67945 0.3048)
			(stroke
				(width 0.1)
				(type default)
			)
			(layer "F.Fab")
		)
		(fp_line
			(start 0.120396 0.3048)
			(end 0.120396 0.2794)
			(stroke
				(width 0.1)
				(type default)
			)
			(layer "F.Fab")
		)
		(fp_line
			(start 0.67945 0.3048)
			(end 0.120396 0.3048)
			(stroke
				(width 0.1)
				(type default)
			)
			(layer "F.Fab")
		)
		(fp_line
			(start -0.12065 0.2794)
			(end -0.12065 0.3048)
			(stroke
				(width 0.1)
				(type default)
			)
			(layer "F.Fab")
		)
		(fp_line
			(start 0.120396 0.2794)
			(end -0.12065 0.2794)
			(stroke
				(width 0.1)
				(type default)
			)
			(layer "F.Fab")
		)
		(fp_line
			(start -0.12065 -0.2794)
			(end 0.12065 -0.2794)
			(stroke
				(width 0.1)
				(type default)
			)
			(layer "F.Fab")
		)
		(fp_line
			(start 0.12065 -0.2794)
			(end 0.12065 -0.3048)
			(stroke
				(width 0.1)
				(type default)
			)
			(layer "F.Fab")
		)
		(fp_line
			(start 0.12065 -0.3048)
			(end 0.67945 -0.3048)
			(stroke
				(width 0.1)
				(type default)
			)
			(layer "F.Fab")
		)
		(fp_line
			(start 0.67945 -0.3048)
			(end 0.67945 0.3048)
			(stroke
				(width 0.1)
				(type default)
			)
			(layer "F.Fab")
		)
		(fp_line
			(start -0.67945 -0.305054)
			(end -0.12065 -0.305054)
			(stroke
				(width 0.1)
				(type default)
			)
			(layer "F.Fab")
		)
		(fp_line
			(start -0.12065 -0.305054)
			(end -0.12065 -0.2794)
			(stroke
				(width 0.1)
				(type default)
			)
			(layer "F.Fab")
		)
		(pad "1" smd circle
			(at -0.40005 0 270)
			(size 0 0)
			(layers "F.Cu" "F.Mask" "F.Paste")
			(net "TCA9539_0_ADD1")
		)
		(pad "2" smd circle
			(at 0.40005 0 270)
			(size 0 0)
			(layers "F.Cu" "F.Mask" "F.Paste")
			(net "GND")
		)
	)
	(footprint ""
		(layer "F.Cu")
		(at 85.576156 -95.992442)
		(property "Reference" "Q85"
			(at -5.17652 -0.638048 0)
			(unlocked yes)
			(layer "F.SilkS")
			(effects
				(font
					(size 0.7874 0.5842)
					(thickness 0.1524)
				)
				(justify left)
			)
		)
		(property "Value" ""
			(at 0 0 0)
			(layer "F.Fab")
			(effects
				(font
					(size 1.27 1.27)
				)
			)
		)
		(duplicate_pad_numbers_are_jumpers no)
		(fp_line
			(start -1.332738 -1.100074)
			(end -0.4826 -1.100074)
			(stroke
				(width 0.1524)
				(type default)
			)
			(layer "F.SilkS")
		)
		(fp_line
			(start -1.332738 1.100074)
			(end -1.332738 -1.100074)
			(stroke
				(width 0.1524)
				(type default)
			)
			(layer "F.SilkS")
		)
		(fp_line
			(start -0.4826 -1.100074)
			(end 0 -0.541274)
			(stroke
				(width 0.1524)
				(type default)
			)
			(layer "F.SilkS")
		)
		(fp_line
			(start 0 -0.541274)
			(end 0.4826 -1.100074)
			(stroke
				(width 0.1524)
				(type default)
			)
			(layer "F.SilkS")
		)
		(fp_line
			(start 0.4826 -1.100074)
			(end 1.332738 -1.100074)
			(stroke
				(width 0.1524)
				(type default)
			)
			(layer "F.SilkS")
		)
		(fp_line
			(start 1.332738 -1.100074)
			(end 1.332738 1.100074)
			(stroke
				(width 0.1524)
				(type default)
			)
			(layer "F.SilkS")
		)
		(fp_line
			(start 1.332738 1.100074)
			(end -1.332738 1.100074)
			(stroke
				(width 0.1524)
				(type default)
			)
			(layer "F.SilkS")
		)
		(fp_poly
			(pts
				(xy -2.2352 -1.001014) (xy -1.533144 -0.649986) (xy -2.2352 -0.298958)
			)
			(stroke
				(width 0)
				(type default)
			)
			(fill yes)
			(layer "F.SilkS")
		)
		(fp_line
			(start -0.674878 -1.100074)
			(end 0.674878 -1.100074)
			(stroke
				(width 0.1)
				(type default)
			)
			(layer "F.Fab")
		)
		(fp_line
			(start -0.674878 1.100074)
			(end -0.674878 -1.100074)
			(stroke
				(width 0.1)
				(type default)
			)
			(layer "F.Fab")
		)
		(fp_line
			(start 0.674878 -1.100074)
			(end 0.674878 1.100074)
			(stroke
				(width 0.1)
				(type default)
			)
			(layer "F.Fab")
		)
		(fp_line
			(start 0.674878 1.100074)
			(end -0.674878 1.100074)
			(stroke
				(width 0.1)
				(type default)
			)
			(layer "F.Fab")
		)
		(fp_poly
			(pts
				(xy -2.2352 -0.298958) (xy -2.2352 -1.001014) (xy -1.533144 -0.649986)
			)
			(stroke
				(width 0)
				(type default)
			)
			(fill yes)
			(layer "F.Fab")
		)
		(pad "1" smd rect
			(at -0.94996 -0.649986 90)
			(size 0.4318 0.508)
			(layers "F.Cu" "F.Mask" "F.Paste")
			(net "GND")
		)
		(pad "2" smd rect
			(at -0.94996 0 90)
			(size 0.4318 0.508)
			(layers "F.Cu" "F.Mask" "F.Paste")
			(net "PWRGD_PVCCFA_EHV_CPU1")
		)
		(pad "3" smd rect
			(at -0.94996 0.649986 90)
			(size 0.4318 0.508)
			(layers "F.Cu" "F.Mask" "F.Paste")
			(net "LED_PWRGD_PVCCFA_EHV_FIVRA_CP_2")
		)
		(pad "4" smd rect
			(at 0.94996 0.649986 90)
			(size 0.4318 0.508)
			(layers "F.Cu" "F.Mask" "F.Paste")
			(net "GND")
		)
		(pad "5" smd rect
			(at 0.94996 0 90)
			(size 0.4318 0.508)
			(layers "F.Cu" "F.Mask" "F.Paste")
			(net "PWRGD_PVCCFA_EHV_FIVRA_CPU1")
		)
		(pad "6" smd rect
			(at 0.94996 -0.649986 90)
			(size 0.4318 0.508)
			(layers "F.Cu" "F.Mask" "F.Paste")
			(net "LED_PWRGD_PVCCFA_EHV_CPU1_D")
		)
	)
	(footprint ""
		(layer "F.Cu")
		(at 294.95242 -424.00601 90)
		(property "Reference" "Q134"
			(at -7.737602 10.748772 90)
			(unlocked yes)
			(layer "F.SilkS")
			(effects
				(font
					(size 0.7874 0.5842)
					(thickness 0.1524)
				)
				(justify left)
			)
		)
		(property "Value" ""
			(at 0 0 90)
			(layer "F.Fab")
			(effects
				(font
					(size 1.27 1.27)
				)
			)
		)
		(duplicate_pad_numbers_are_jumpers no)
		(fp_line
			(start 1.332738 -1.100074)
			(end 1.332738 1.100074)
			(stroke
				(width 0.1524)
				(type default)
			)
			(layer "F.SilkS")
		)
		(fp_line
			(start 0.4826 -1.100074)
			(end 1.332738 -1.100074)
			(stroke
				(width 0.1524)
				(type default)
			)
			(layer "F.SilkS")
		)
		(fp_line
			(start -0.4826 -1.100074)
			(end 0 -0.541274)
			(stroke
				(width 0.1524)
				(type default)
			)
			(layer "F.SilkS")
		)
		(fp_line
			(start -1.332738 -1.100074)
			(end -0.4826 -1.100074)
			(stroke
				(width 0.1524)
				(type default)
			)
			(layer "F.SilkS")
		)
		(fp_line
			(start 0 -0.541274)
			(end 0.4826 -1.100074)
			(stroke
				(width 0.1524)
				(type default)
			)
			(layer "F.SilkS")
		)
		(fp_line
			(start 1.332738 1.100074)
			(end -1.332738 1.100074)
			(stroke
				(width 0.1524)
				(type default)
			)
			(layer "F.SilkS")
		)
		(fp_line
			(start -1.332738 1.100074)
			(end -1.332738 -1.100074)
			(stroke
				(width 0.1524)
				(type default)
			)
			(layer "F.SilkS")
		)
		(fp_poly
			(pts
				(xy -1.760728 -1.63322) (xy -1.51257 -0.888746) (xy -2.257044 -1.136904)
			)
			(stroke
				(width 0)
				(type default)
			)
			(fill yes)
			(layer "F.SilkS")
		)
		(fp_line
			(start 0.674878 -1.100074)
			(end 0.674878 1.100074)
			(stroke
				(width 0.1)
				(type default)
			)
			(layer "F.Fab")
		)
		(fp_line
			(start -0.674878 -1.100074)
			(end 0.674878 -1.100074)
			(stroke
				(width 0.1)
				(type default)
			)
			(layer "F.Fab")
		)
		(fp_line
			(start 0.674878 1.100074)
			(end -0.674878 1.100074)
			(stroke
				(width 0.1)
				(type default)
			)
			(layer "F.Fab")
		)
		(fp_line
			(start -0.674878 1.100074)
			(end -0.674878 -1.100074)
			(stroke
				(width 0.1)
				(type default)
			)
			(layer "F.Fab")
		)
		(fp_poly
			(pts
				(xy -2.2352 -0.298958) (xy -2.2352 -1.001014) (xy -1.533144 -0.649986)
			)
			(stroke
				(width 0)
				(type default)
			)
			(fill yes)
			(layer "F.Fab")
		)
		(pad "1" smd rect
			(at -0.94996 -0.649986 180)
			(size 0.4318 0.508)
			(layers "F.Cu" "F.Mask" "F.Paste")
			(net "GND")
		)
		(pad "2" smd rect
			(at -0.94996 0 180)
			(size 0.4318 0.508)
			(layers "F.Cu" "F.Mask" "F.Paste")
			(net "PRSNT_CABLE_GPU_A1_N")
		)
		(pad "3" smd rect
			(at -0.94996 0.649986 180)
			(size 0.4318 0.508)
			(layers "F.Cu" "F.Mask" "F.Paste")
			(net "PRSNT_CABLE_GPU_A1_ISO_N")
		)
		(pad "4" smd rect
			(at 0.94996 0.649986 180)
			(size 0.4318 0.508)
			(layers "F.Cu" "F.Mask" "F.Paste")
			(net "GND")
		)
		(pad "5" smd rect
			(at 0.94996 0 180)
			(size 0.4318 0.508)
			(layers "F.Cu" "F.Mask" "F.Paste")
			(net "PRSNT_CABLE_GPU_A1")
		)
		(pad "6" smd rect
			(at 0.94996 -0.649986 180)
			(size 0.4318 0.508)
			(layers "F.Cu" "F.Mask" "F.Paste")
			(net "PRSNT_CABLE_GPU_A1")
		)
	)
)
